# T6G (Grand Teton) — schematic netlist excerpt (pin names and nets, part order shuffled) for the footprints in the layout excerpt that follows; sources: Cadence DE-HDL packaged netlist, KiCad conversion of 04192023_DAF0TMB3IC0_F0TG_MB_C_brd_V02_OCP.brd

PU5  ISL99390FRZTR5935  ISL99390FRZ-TR5935 IC  pkg QFN21_6X5XB  page 218
  VOS  = PVDDCR_CPU1_P1_VOS2
  AGND  = GND
  VCC  = PVDDCR_CPU1_P1_VCC2
  PVCC  = PVDDCR_CPU1_P1_PVCC
  PGND1  = GND
  GL1  = NC_PVDDCR_CPU1_P1_GL1_2
  PGND2  = GND
  SW  = SW_PVDDCR_CPU1_P1_SW2
  VIN1  = SW_P12V_AUX_PVDDCR_CPU1_P1_FLT
  VIN2  = SW_P12V_AUX_PVDDCR_CPU1_P1_FLT
  DNC  = NC_PVDDCR_CPU1_P1_DNC2
  PHASE  = SW_PVDDCR_CPU1_P1_BOOTR2
  BOOT  = SW_PVDDCR_CPU1_P1_BOOT2
  PWM  = PVDDCR_CPU1_P1_PWM2
  EN  = PVDDCR_CPU1_P1_VCC2
  TOUT_FLT  = PVDDCR_CPU1_P1_TEMP0
  LSET  = PVDDCR_CPU1_P1_LSET2
  IOUT  = PVDDCR_CPU1_P1_IMON2
  REFIN  = PVDDCR_CPU1_P1_VCCS
  PGND3  = GND
  GL2  = NC_PVDDCR_CPU1_P1_GL2_2

(kicad_pcb
	(version 20260206)
	(generator "pcbnew")
	(generator_version "10.0")
	(general
		(thickness 1.6)
		(legacy_teardrops no)
	)
	(paper "A4")
	(title_block
		(title "04192023_DAF0TMB3IC0_F0TG_MB_C_brd_V02_OCP.brd")
		(comment 1 "Grand Teton / footprints 3580-3580 of 8354")
	)
	(layers
		(0 "F.Cu" signal "TOP")
		(4 "In1.Cu" signal "GND")
		(6 "In2.Cu" signal "IN1")
		(8 "In3.Cu" signal "GND1")
		(10 "In4.Cu" signal "IN2")
		(12 "In5.Cu" signal "GND2")
		(14 "In6.Cu" signal "IN3")
		(16 "In7.Cu" signal "GND3")
		(18 "In8.Cu" signal "VCC")
		(20 "In9.Cu" signal "VCC1")
		(22 "In10.Cu" signal "GND4")
		(24 "In11.Cu" signal "IN4")
		(26 "In12.Cu" signal "GND5")
		(28 "In13.Cu" signal "IN5")
		(30 "In14.Cu" signal "GND6")
		(32 "In15.Cu" signal "IN6")
		(34 "In16.Cu" signal "GND7")
		(2 "B.Cu" signal "BOTTOM")
		(9 "F.Adhes" user "F.Adhesive")
		(11 "B.Adhes" user "B.Adhesive")
		(13 "F.Paste" user "Package Geometry/Pastemask Top")
		(15 "B.Paste" user "Package Geometry/Pastemask Bottom")
		(5 "F.SilkS" user "Ref Des/Silkscreen Top")
		(7 "B.SilkS" user "Ref Des/Silkscreen Bottom")
		(1 "F.Mask" user "Board Geometry/Soldermask Top")
		(3 "B.Mask" user "Board Geometry/Soldermask Bottom")
		(17 "Dwgs.User" user "User.Drawings")
		(19 "Cmts.User" user "User.Comments")
		(21 "Eco1.User" user "User.Eco1")
		(23 "Eco2.User" user "User.Eco2")
		(25 "Edge.Cuts" user "Board Geometry/Outline")
		(27 "Margin" user)
		(31 "F.CrtYd" user "Package Geometry/Place Bound Top")
		(29 "B.CrtYd" user "Package Geometry/Place Bound Bottom")
		(35 "F.Fab" user "Ref Des/Assembly Top")
		(33 "B.Fab" user "Ref Des/Assembly Bottom")
	)
	(footprint ""
		(layer "F.Cu")
		(at 78.764638 -334.99298)
		(property "Reference" "PU5"
			(at -0.659638 -8.51535 0)
			(unlocked yes)
			(layer "F.SilkS")
			(effects
				(font
					(size 0.7874 0.5842)
					(thickness 0.1524)
				)
				(justify left)
			)
		)
		(property "Value" ""
			(at 0 0 0)
			(layer "F.Fab")
			(effects
				(font
					(size 1.27 1.27)
				)
			)
		)
		(duplicate_pad_numbers_are_jumpers no)
		(fp_line
			(start -2.500122 -2.999994)
			(end -2.24409 -2.999994)
			(stroke
				(width 0.1524)
				(type default)
			)
			(layer "F.SilkS")
		)
		(fp_line
			(start -2.500122 -2.529078)
			(end -2.500122 -2.999994)
			(stroke
				(width 0.1524)
				(type default)
			)
			(layer "F.SilkS")
		)
		(fp_line
			(start -2.500122 0.6604)
			(end -2.500122 0.229108)
			(stroke
				(width 0.1524)
				(type default)
			)
			(layer "F.SilkS")
		)
		(fp_line
			(start -2.500122 2.999994)
			(end -2.500122 2.339594)
			(stroke
				(width 0.1524)
				(type default)
			)
			(layer "F.SilkS")
		)
		(fp_line
			(start -2.2987 2.999994)
			(end -2.500122 2.999994)
			(stroke
				(width 0.1524)
				(type default)
			)
			(layer "F.SilkS")
		)
		(fp_line
			(start 2.31394 -2.999994)
			(end 2.500122 -2.999994)
			(stroke
				(width 0.1524)
				(type default)
			)
			(layer "F.SilkS")
		)
		(fp_line
			(start 2.500122 -2.999994)
			(end 2.500122 -2.44348)
			(stroke
				(width 0.1524)
				(type default)
			)
			(layer "F.SilkS")
		)
		(fp_line
			(start 2.500122 2.339594)
			(end 2.500122 2.999994)
			(stroke
				(width 0.1524)
				(type default)
			)
			(layer "F.SilkS")
		)
		(fp_line
			(start 2.500122 2.999994)
			(end 2.2987 2.999994)
			(stroke
				(width 0.1524)
				(type default)
			)
			(layer "F.SilkS")
		)
		(fp_poly
			(pts
				(xy -2.7686 -2.321306) (xy -3.441954 -2.545842) (xy -2.993136 -2.994914)
			)
			(stroke
				(width 0)
				(type default)
			)
			(fill yes)
			(layer "F.SilkS")
		)
		(fp_line
			(start -2.500122 -2.999994)
			(end 2.500122 -2.999994)
			(stroke
				(width 0.1)
				(type default)
			)
			(layer "F.Fab")
		)
		(fp_line
			(start -2.500122 2.999994)
			(end -2.500122 -2.999994)
			(stroke
				(width 0.1)
				(type default)
			)
			(layer "F.Fab")
		)
		(fp_line
			(start 2.500122 -2.999994)
			(end 2.500122 2.999994)
			(stroke
				(width 0.1)
				(type default)
			)
			(layer "F.Fab")
		)
		(fp_line
			(start 2.500122 2.999994)
			(end -2.500122 2.999994)
			(stroke
				(width 0.1)
				(type default)
			)
			(layer "F.Fab")
		)
		(fp_poly
			(pts
				(xy -4.218432 -2.783078) (xy -4.218432 -1.767078) (xy -3.202432 -2.275078)
			)
			(stroke
				(width 0)
				(type default)
			)
			(fill yes)
			(layer "F.Fab")
		)
		(pad "1" smd rect
			(at -2.400046 -2.275078 90)
			(size 0.2286 0.6096)
			(layers "F.Cu" "F.Mask" "F.Paste")
			(net "PVDDCR_CPU1_P1_VOS2")
		)
		(pad "2" smd rect
			(at -2.400046 -1.82499 90)
			(size 0.2286 0.6096)
			(layers "F.Cu" "F.Mask" "F.Paste")
			(net "GND")
		)
		(pad "3" smd rect
			(at -2.400046 -1.374902 90)
			(size 0.2286 0.6096)
			(layers "F.Cu" "F.Mask" "F.Paste")
			(net "PVDDCR_CPU1_P1_VCC2")
		)
		(pad "4" smd rect
			(at -2.400046 -0.925068 90)
			(size 0.2286 0.6096)
			(layers "F.Cu" "F.Mask" "F.Paste")
			(net "PVDDCR_CPU1_P1_PVCC")
		)
		(pad "5" smd rect
			(at -2.400046 -0.47498 90)
			(size 0.2286 0.6096)
			(layers "F.Cu" "F.Mask" "F.Paste")
			(net "GND")
		)
		(pad "6" smd rect
			(at -2.400046 -0.024892 90)
			(size 0.2286 0.6096)
			(layers "F.Cu" "F.Mask" "F.Paste")
			(net "NC_PVDDCR_CPU1_P1_GL1_2")
		)
		(pad "7_9-20_24" smd circle
			(at 0 1.150112 90)
			(size 0 0)
			(layers "F.Cu" "F.Mask" "F.Paste")
			(net "GND")
		)
		(pad "10_19" smd rect
			(at 0 2.899918 90)
			(size 0.6096 4.318)
			(layers "F.Cu" "F.Mask" "F.Paste")
			(net "SW_PVDDCR_CPU1_P1_SW2")
		)
		(pad "25_29" smd rect
			(at 1.549908 -1.279906 270)
			(size 2.0574 2.3114)
			(layers "F.Cu" "F.Mask" "F.Paste")
			(net "SW_P12V_AUX_PVDDCR_CPU1_P1_FLT")
		)
		(pad "30" smd rect
			(at 2.05994 -2.899918)
			(size 0.2286 0.6096)
			(layers "F.Cu" "F.Mask" "F.Paste")
			(net "SW_P12V_AUX_PVDDCR_CPU1_P1_FLT")
		)
		(pad "31" smd rect
			(at 1.610106 -2.899918)
			(size 0.2286 0.6096)
			(layers "F.Cu" "F.Mask" "F.Paste")
			(net "NC_PVDDCR_CPU1_P1_DNC2")
		)
		(pad "32" smd rect
			(at 1.160018 -2.899918)
			(size 0.2286 0.6096)
			(layers "F.Cu" "F.Mask" "F.Paste")
			(net "SW_PVDDCR_CPU1_P1_BOOTR2")
		)
		(pad "33" smd rect
			(at 0.70993 -2.899918)
			(size 0.2286 0.6096)
			(layers "F.Cu" "F.Mask" "F.Paste")
			(net "SW_PVDDCR_CPU1_P1_BOOT2")
		)
		(pad "34" smd rect
			(at 0.260096 -2.899918)
			(size 0.2286 0.6096)
			(layers "F.Cu" "F.Mask" "F.Paste")
			(net "PVDDCR_CPU1_P1_PWM2")
		)
		(pad "35" smd rect
			(at -0.189992 -2.899918)
			(size 0.2286 0.6096)
			(layers "F.Cu" "F.Mask" "F.Paste")
			(net "PVDDCR_CPU1_P1_VCC2")
		)
		(pad "36" smd rect
			(at -0.64008 -2.899918)
			(size 0.2286 0.6096)
			(layers "F.Cu" "F.Mask" "F.Paste")
			(net "PVDDCR_CPU1_P1_TEMP0")
		)
		(pad "37" smd rect
			(at -1.089914 -2.899918)
			(size 0.2286 0.6096)
			(layers "F.Cu" "F.Mask" "F.Paste")
			(net "PVDDCR_CPU1_P1_LSET2")
		)
		(pad "38" smd rect
			(at -1.540002 -2.899918)
			(size 0.2286 0.6096)
			(layers "F.Cu" "F.Mask" "F.Paste")
			(net "PVDDCR_CPU1_P1_IMON2")
		)
		(pad "39" smd rect
			(at -1.99009 -2.899918)
			(size 0.2286 0.6096)
			(layers "F.Cu" "F.Mask" "F.Paste")
			(net "PVDDCR_CPU1_P1_VCCS")
		)
		(pad "40" smd rect
			(at -0.87503 -1.27508)
			(size 1.7526 1.9558)
			(layers "F.Cu" "F.Mask" "F.Paste")
			(net "GND")
		)
		(pad "41" smd rect
			(at -1.525016 0.249936 270)
			(size 0.3048 0.4572)
			(layers "F.Cu" "F.Mask" "F.Paste")
			(net "NC_PVDDCR_CPU1_P1_GL2_2")
		)
		(zone
			(layer "F.Cu")
			(hatch none 0.5)
			(connect_pads
				(clearance 0)
			)
			(min_thickness 0.25)
			(keepout
				(tracks not_allowed)
				(vias allowed)
				(pads allowed)
				(copperpour not_allowed)
				(footprints allowed)
			)
			(placement
				(enabled no)
				(sheetname "")
			)
			(fill
				(thermal_gap 0.5)
				(thermal_bridge_width 0.5)
				(island_removal_mode 0)
			)
			(polygon
				(pts
					(xy 76.264516 -332.394052) (xy 76.264516 -332.742286) (xy 81.26476 -332.742286) (xy 81.26476 -332.420976)
					(xy 80.974438 -332.420976) (xy 80.974438 -332.448662) (xy 76.554838 -332.448662) (xy 76.554838 -332.394052)
				)
			)
		)
		(zone
			(layer "F.Cu")
			(hatch none 0.5)
			(connect_pads
				(clearance 0)
			)
			(min_thickness 0.25)
			(keepout
				(tracks not_allowed)
				(vias allowed)
				(pads allowed)
				(copperpour not_allowed)
				(footprints allowed)
			)
			(placement
				(enabled no)
				(sheetname "")
			)
			(fill
				(thermal_gap 0.5)
				(thermal_bridge_width 0.5)
				(island_removal_mode 0)
			)
			(polygon
				(pts
					(xy 78.816708 -335.23936) (xy 78.816708 -337.29676) (xy 76.962508 -337.29676) (xy 76.962508 -337.055714)
					(xy 76.720192 -337.055714) (xy 76.720192 -337.537298) (xy 80.504538 -337.537298) (xy 80.504538 -337.352386)
					(xy 79.108046 -337.352386) (xy 79.108046 -335.193386) (xy 81.26476 -335.193386) (xy 81.26476 -334.943704)
					(xy 79.112364 -334.943704)
				)
			)
		)
	)
)
